FILE_TYPE = MACRO_DRAWING;
SET COLOR_WIRE YELLOW;
SET COLOR_PROP ORANGE;
SET COLOR_DOT WHITE;
SET COLOR_ARC YELLOW;
SET COLOR_BODY GREEN;
SET COLOR_NOTE PURPLE;
SET PROP_DISPLAY VALUE;
SET PAGE_NUMBER P140;
FORCEADD QUANTA_TITLE_BLOCK_C..1
(9675 -750);
FORCEPROP 1 LAST CUSTOM_TXT_CDS <NAME_2>
J 0
(6500 -700);
FORCEPROP 1 LAST CUSTOM_TXT_CDS <NAME_1>
J 0
(6500 -575);
FORCEPROP 1 LAST CUSTOM_TXT_CDS <Q_NUMBER>
J 0
(8272 -647);
DISPLAY 1.212766 (8272 -647);
FORCEPROP 1 LAST CUSTOM_TXT_CDS <Q_PROJ>
J 0
(7293 -648);
DISPLAY 1.212766 (7293 -648);
FORCEPROP 1 LAST CUSTOM_TXT_CDS <Q_REV>
J 0
(9491 -647);
DISPLAY 1.212766 (9491 -647);
FORCEPROP 1 LAST CUSTOM_TXT_CDS <CON_LAST_MODIFIED>
J 0
(7790 -735);
DISPLAY 0.978723 (7790 -735);
FORCEPROP 1 LAST CUSTOM_TXT_CDS <CON_PAGE_NUM> OF <CON_TOTAL_PAGES>
J 0
(9229 -732);
DISPLAY 0.978723 (9229 -732);
FORCEPROP 1 LAST Q_DEPT BU9
J 1
(5912 -701);
DISPLAY 1.957447 (5912 -701);
PAINT GREEN (5912 -701);
FORCEPROP 1 LAST Q_TITLE LIQUID DETECTION
J 0
(375 -675);
DISPLAY 2.446809 (375 -675);
PAINT GREEN (375 -675);
FORCEPROP 2 LAST CDS_LIB pure_quanta
J 0
(9675 -750);
DISPLAY INVISIBLE (9675 -750);
FORCEPROP 1 LAST CDS_LMAN_SYM_OUTLINE -9475,6775,100,-125
J 0
(9675 -750);
DISPLAY 0.468085 (9675 -750);
PAINT GREEN (9675 -750);
DISPLAY INVISIBLE (9675 -750);
FORCEPROP 2 LAST PAGE_BORDER TRUE
J 0
(1785 4500);
DISPLAY 0.638298 (1785 4500);
PAINT PINK (1785 4500);
DISPLAY INVISIBLE (1785 4500);
FORCEPROP 1 LAST COMMENT_BODY TRUE
J 0
(9687 -763);
DISPLAY 0.978723 (9687 -763);
PAINT GREEN (9687 -763);
DISPLAY INVISIBLE (9687 -763);
FORCEPROP 2 LAST CDS_XR_PAGE_TITLE CR-140 : @T6G_MB_LIB.T6G(SCH_1):PAGE140
J 0
(1785 4500);
DISPLAY 0.638298 (1785 4500);
PAINT PINK (1785 4500);
DISPLAY INVISIBLE (1785 4500);
FORCEPROP 2 LAST CUSTOM_TXT_CDS <XR_PAGE_TITLE>
J 0
(1785 4500);
DISPLAY 0.638298 (1785 4500);
PAINT PINK (1785 4500);
DISPLAY INVISIBLE (1785 4500);
FORCEPROP 0 LAST CDS_CON_LAST_MODIFIED Wed Mar 09 19:38:13 2022
J 0
(7790 -735);
DISPLAY INVISIBLE (7790 -735);
QUIT
